FILE_TYPE = CONNECTIVITY;
{Allegro Design Entry HDL 16.6-p007 (v16-6-112F) 10/10/2012}
"PAGE_NUMBER" = 51;
0"NC";
1"M_E_DQS_DN<17:0>";
2"M_E_DQS_DP<17:0>";
3"M_E_MA<17:0>";
4"M_E_DQ<63:0>";
5"M_E_BG<1:0>";
6"M_E_BA<1:0>";
7"M_E_CS_N<7:0>";
8"M_E_ODT<3:0>";
9"M_E_ECC<7:0>";
10"M_E_CLK_DN<3:0>";
11"M_E_CLK_DP<3:0>";
12"M_E_CKE<3:0>";
13"PVDDQ_DEF\g";
14"GND\g";
15"PVTT_DEF\g";
16"GND\g";
17"GND\g";
18"PVPP_DEF\g";
19"PVPP_DEF\g";
20"P12V_NVDIMM_DEF\g";
21"GND\g";
22"M_E_VREF";
23"TP_CH_E_DIMM_E0_RFU_1";
24"TP_CH_E_DIMM_E0_RFU_0";
25"TP_CH_E_DIMM_E0_RFU_2";
26"SMB_DDR_DEF_VPP_SCL";
27"SMB_DDR_DEF_VPP_SDA";
28"FM_ADR_COMPLETE_DEF_N";
29"FM_DIMM_EVENT_COD_N";
30"M_DEF_RST_N";
31"M_E_PAR";
32"M_E_CKE<0>";
33"M_E_CLK_DP<1>";
34"M_E_CKE<1>";
35"M_E_CLK_DP<0>";
36"M_E_CLK_DN<0>";
37"M_E_CLK_DN<1>";
38"M_E_ACT_N";
39"M_E_ALERT_N";
40"M_E_ECC<1>";
41"M_E_ECC<0>";
42"M_E_ECC<3>";
43"M_E_ECC<2>";
44"M_E_ECC<5>";
45"M_E_ECC<4>";
46"M_E_ECC<7>";
47"M_E_ODT<1>";
48"M_E_ODT<0>";
49"M_E_ECC<6>";
50"M_E_CS_N<0>";
51"M_E_CS_N<1>";
52"M_E_C<2>";
53"M_E_CS_N<2>";
54"M_E_CS_N<3>";
55"M_E_BG<0>";
56"M_E_BA<0>";
57"M_E_BG<1>";
58"M_E_MA<0>";
59"M_E_BA<1>";
60"M_E_DQ<4>";
61"M_E_DQ<5>";
62"M_E_DQ<2>";
63"M_E_DQ<3>";
64"M_E_DQ<1>";
65"M_E_DQ<0>";
66"M_E_DQ<14>";
67"M_E_DQ<7>";
68"M_E_DQ<6>";
69"M_E_DQ<9>";
70"M_E_DQ<11>";
71"M_E_DQ<10>";
72"M_E_DQ<13>";
73"M_E_DQ<15>";
74"M_E_DQ<17>";
75"M_E_DQ<8>";
76"M_E_DQ<12>";
77"M_E_DQ<16>";
78"M_E_DQ<27>";
79"M_E_DQ<19>";
80"M_E_DQ<18>";
81"M_E_DQ<21>";
82"M_E_DQ<23>";
83"M_E_DQ<22>";
84"M_E_DQ<25>";
85"M_E_DQ<24>";
86"M_E_DQ<20>";
87"M_E_DQ<26>";
88"M_E_DQ<37>";
89"M_E_DQ<34>";
90"M_E_DQ<31>";
91"M_E_DQ<30>";
92"M_E_DQ<33>";
93"M_E_DQ<32>";
94"M_E_DQ<35>";
95"M_E_DQ<29>";
96"M_E_DQ<28>";
97"M_E_DQ<39>";
98"M_E_DQ<36>";
99"M_E_DQ<38>";
100"M_E_DQ<41>";
101"M_E_DQ<40>";
102"M_E_DQ<43>";
103"M_E_DQ<42>";
104"M_E_DQ<45>";
105"M_E_DQ<44>";
106"M_E_DQ<47>";
107"M_E_MA<2>";
108"M_E_MA<6>";
109"M_E_MA<5>";
110"M_E_MA<4>";
111"M_E_MA<3>";
112"M_E_MA<1>";
113"M_E_MA<11>";
114"M_E_MA<10>";
115"M_E_MA<9>";
116"M_E_MA<8>";
117"M_E_MA<7>";
118"M_E_MA<16>";
119"M_E_MA<15>";
120"M_E_MA<14>";
121"M_E_MA<13>";
122"M_E_MA<12>";
123"M_E_MA<17>";
124"M_E_DQ<46>";
125"M_E_DQ<49>";
126"M_E_DQ<48>";
127"M_E_DQ<51>";
128"M_E_DQ<50>";
129"M_E_DQ<53>";
130"M_E_DQ<52>";
131"M_E_DQ<55>";
132"M_E_DQ<56>";
133"M_E_DQ<54>";
134"M_E_DQ<57>";
135"M_E_DQ<62>";
136"M_E_DQ<63>";
137"M_E_DQ<60>";
138"M_E_DQ<59>";
139"M_E_DQ<58>";
140"M_E_DQ<61>";
141"M_E_DQS_DP<6>";
142"M_E_DQS_DN<6>";
143"M_E_DQS_DP<5>";
144"M_E_DQS_DN<5>";
145"M_E_DQS_DP<4>";
146"M_E_DQS_DN<4>";
147"M_E_DQS_DP<3>";
148"M_E_DQS_DN<3>";
149"M_E_DQS_DP<2>";
150"M_E_DQS_DN<2>";
151"M_E_DQS_DP<1>";
152"M_E_DQS_DN<1>";
153"M_E_DQS_DP<0>";
154"M_E_DQS_DN<0>";
155"M_E_DQS_DP<9>";
156"M_E_DQS_DN<9>";
157"M_E_DQS_DP<8>";
158"M_E_DQS_DN<8>";
159"M_E_DQS_DP<7>";
160"M_E_DQS_DN<7>";
161"M_E_DQS_DN<17>";
162"M_E_DQS_DP<16>";
163"M_E_DQS_DN<16>";
164"M_E_DQS_DP<15>";
165"M_E_DQS_DN<15>";
166"M_E_DQS_DP<14>";
167"M_E_DQS_DN<14>";
168"M_E_DQS_DP<13>";
169"M_E_DQS_DN<13>";
170"M_E_DQS_DP<12>";
171"M_E_DQS_DN<12>";
172"M_E_DQS_DP<11>";
173"M_E_DQS_DN<11>";
174"M_E_DQS_DP<10>";
175"M_E_DQS_DN<10>";
176"M_E_DQS_DP<17>";
%"TAP"
"6","(700,5050)","2","mstr_standard","I10";
;
HDL_TAP"TRUE"
BODY_TYPE"PLUMBING"
CDS_LIB"mstr_standard";
"B \NAC \NWC"2;
"S \NAC"
BN"16"162;
%"TAP"
"6","(-1600,2250)","2","mstr_standard","I100";
;
HDL_TAP"TRUE"
BODY_TYPE"PLUMBING"
CDS_LIB"mstr_standard";
"B \NAC \NWC"4;
"S \NAC"
BN"11"70;
%"TAP"
"6","(-1600,2200)","2","mstr_standard","I101";
;
HDL_TAP"TRUE"
BODY_TYPE"PLUMBING"
CDS_LIB"mstr_standard";
"B \NAC \NWC"4;
"S \NAC"
BN"8"75;
%"TAP"
"6","(-1600,2100)","2","mstr_standard","I102";
;
HDL_TAP"TRUE"
BODY_TYPE"PLUMBING"
CDS_LIB"mstr_standard";
"B \NAC \NWC"4;
"S \NAC"
BN"6"68;
%"TAP"
"6","(-1600,2150)","2","mstr_standard","I103";
;
HDL_TAP"TRUE"
BODY_TYPE"PLUMBING"
CDS_LIB"mstr_standard";
"B \NAC \NWC"4;
"S \NAC"
BN"9"69;
%"TAP"
"6","(-1600,2050)","2","mstr_standard","I104";
;
HDL_TAP"TRUE"
BODY_TYPE"PLUMBING"
CDS_LIB"mstr_standard";
"B \NAC \NWC"4;
"S \NAC"
BN"7"67;
%"TAP"
"6","(-1600,2000)","2","mstr_standard","I105";
;
HDL_TAP"TRUE"
BODY_TYPE"PLUMBING"
CDS_LIB"mstr_standard";
"B \NAC \NWC"4;
"S \NAC"
BN"4"60;
%"TAP"
"6","(-1600,1900)","2","mstr_standard","I106";
;
HDL_TAP"TRUE"
BODY_TYPE"PLUMBING"
CDS_LIB"mstr_standard";
"B \NAC \NWC"4;
"S \NAC"
BN"2"62;
%"TAP"
"6","(-1600,1950)","2","mstr_standard","I107";
;
HDL_TAP"TRUE"
BODY_TYPE"PLUMBING"
CDS_LIB"mstr_standard";
"B \NAC \NWC"4;
"S \NAC"
BN"5"61;
%"TAP"
"6","(-1600,1800)","2","mstr_standard","I108";
;
HDL_TAP"TRUE"
BODY_TYPE"PLUMBING"
CDS_LIB"mstr_standard";
"B \NAC \NWC"4;
"S \NAC"
BN"0"65;
%"TAP"
"6","(-1600,1850)","2","mstr_standard","I109";
;
HDL_TAP"TRUE"
BODY_TYPE"PLUMBING"
CDS_LIB"mstr_standard";
"B \NAC \NWC"4;
"S \NAC"
BN"3"63;
%"TAP"
"6","(700,4950)","2","mstr_standard","I11";
;
HDL_TAP"TRUE"
BODY_TYPE"PLUMBING"
CDS_LIB"mstr_standard";
"B \NAC \NWC"2;
"S \NAC"
BN"15"164;
%"TAP"
"6","(-1600,1750)","2","mstr_standard","I110";
;
HDL_TAP"TRUE"
BODY_TYPE"PLUMBING"
CDS_LIB"mstr_standard";
"B \NAC \NWC"4;
"S \NAC"
BN"1"64;
%"SCONN288_H44441004"
"1","(-2350,3250)","0","mstr_sconn","I111";
;
CDS_SEC"1"
ROOM"DDR4_CH_E"
CDS_LOCATION"J4A2"
SEC"1"
SEC_TYPE"PIP"
CDS_LIB"mstr_sconn"
BOM_COST"MEM"
PACK_TYPE"PIP"
MATERIAL"SCONN"
PART_NUMBER"H44441-004"
LOCATION"J4A2";
"DQ<63>"
$PN"280"135;
"DQ<62>"
$PN"135"136;
"DQ<61>"
$PN"273"137;
"DQ<5>"
$PN"148"60;
"DQ<4>"
$PN"3"61;
"DQ<3>"
$PN"157"62;
"DQ<2>"
$PN"12"63;
"DQ<47>"
$PN"258"124;
"DQ<48>"
$PN"119"125;
"DQ<49>"
$PN"264"126;
"DQ<50>"
$PN"126"127;
"DQ<51>"
$PN"271"128;
"DQ<52>"
$PN"117"129;
"DQ<53>"
$PN"262"130;
"DQ<54>"
$PN"124"131;
"DQ<58>"
$PN"137"138;
"DQ<57>"
$PN"275"132;
"SAVE_N_NC"
$PN"230"28;
"RFU<1>"
$PN"227"23;
"RFU<0>"
$PN"205"24;
"DQ<17>"
$PN"172"77;
"DQ<15>"
$PN"166"66;
"DQ<26>"
$PN"45"78;
"DQ<27>"
$PN"190"87;
"S0_N"
$PN"84"50;
"CKE<0>"
$PN"60"32;
"ODT<1>"
$PN"91"47;
"ODT<0>"
$PN"87"48;
"CB<7>"
$PN"199"49;
"A16_RAS_N"
$PN"82"118;
"A15_CAS_N"
$PN"86"119;
"A14_WE_N"
$PN"228"120;
"A11"
$PN"210"113;
"A10"
$PN"225"114;
"DQ<38>"
$PN"102"97;
"DQ<36>"
$PN"95"88;
"DQ<35>"
$PN"249"89;
"A2"
$PN"216"107;
"ALERT_N"
$PN"208"39;
"ACT_N"
$PN"62"38;
"DQ<0>"
$PN"5"64;
"DQ<1>"
$PN"150"65;
"SA<1>"
$PN"140"19;
"SA<2>"
$PN"238"16;
"VDDSPD"
$PN"284"19;
"SA<0>"
$PN"139"16;
"BA<0>"
$PN"81"56;
"BG<1>"
$PN"207"57;
"BG<0>"
$PN"63"55;
"CK1P"
$PN"218"33;
"VREFCA"
$PN"146"22;
"SDA"
$PN"285"27;
"SCL"
$PN"141"26;
"RFU<2>"
$PN"144"25;
"RESET_N"
$PN"58"30;
"PAR"
$PN"222"31;
"EVENT_N"
$PN"78"29;
"DQ<6>"
$PN"10"67;
"DQ<7>"
$PN"155"68;
"DQ<8>"
$PN"16"69;
"DQ<9>"
$PN"161"75;
"DQ<10>"
$PN"23"70;
"DQ<11>"
$PN"168"71;
"DQ<12>"
$PN"14"72;
"DQ<13>"
$PN"159"76;
"DQ<14>"
$PN"21"73;
"DQ<16>"
$PN"27"74;
"DQ<18>"
$PN"34"79;
"DQ<19>"
$PN"179"80;
"DQ<20>"
$PN"25"81;
"DQ<21>"
$PN"170"86;
"DQ<22>"
$PN"32"82;
"DQ<23>"
$PN"177"83;
"DQ<24>"
$PN"38"84;
"DQ<25>"
$PN"183"85;
"DQ<30>"
$PN"43"90;
"DQ<31>"
$PN"188"91;
"DQ<32>"
$PN"97"92;
"DQ<33>"
$PN"242"93;
"DQ<34>"
$PN"104"94;
"DQ<37>"
$PN"240"98;
"DQ<39>"
$PN"247"99;
"DQ<40>"
$PN"108"100;
"DQ<41>"
$PN"253"101;
"DQ<42>"
$PN"115"102;
"DQ<43>"
$PN"260"103;
"DQ<44>"
$PN"106"104;
"DQ<45>"
$PN"251"105;
"DQ<46>"
$PN"113"106;
"DQ<55>"
$PN"269"133;
"DQ<56>"
$PN"130"134;
"DQ<59>"
$PN"282"139;
"DQ<60>"
$PN"128"140;
"CKE<1>"
$PN"203"34;
"CK0N"
$PN"75"36;
"CB<0>"
$PN"49"40;
"CB<1>"
$PN"194"41;
"CB<2>"
$PN"56"42;
"CB<3>"
$PN"201"43;
"CB<4>"
$PN"47"44;
"CB<5>"
$PN"192"45;
"CB<6>"
$PN"54"46;
"A9"
$PN"66"115;
"A8"
$PN"68"116;
"A7"
$PN"211"117;
"A6"
$PN"69"108;
"A5"
$PN"213"109;
"A4"
$PN"214"110;
"A3"
$PN"71"111;
"A17"
$PN"234"123;
"A13"
$PN"232"121;
"A12"
$PN"65"122;
"A1"
$PN"72"112;
"A0"
$PN"79"58;
"C<2>"
$PN"235"52;
"DQ<28>"
$PN"36"95;
"DQ<29>"
$PN"181"96;
"S1_N"
$PN"89"51;
"S2_N_C<0>"
$PN"93"53;
"S3_N_C<1>"
$PN"237"54;
"CK0P"
$PN"74"35;
"CK1N"
$PN"219"37;
"BA<1>"
$PN"224"59;
%"TAP"
"6","(-3100,4900)","0","mstr_standard","I112";
;
HDL_TAP"TRUE"
BODY_TYPE"PLUMBING"
CDS_LIB"mstr_standard";
"B \NAC \NWC"3;
"S \NAC"
BN"17"123;
%"TAP"
"6","(-3100,4850)","0","mstr_standard","I113";
;
HDL_TAP"TRUE"
BODY_TYPE"PLUMBING"
CDS_LIB"mstr_standard";
"B \NAC \NWC"3;
"S \NAC"
BN"16"118;
%"TAP"
"6","(-3100,4800)","0","mstr_standard","I114";
;
HDL_TAP"TRUE"
BODY_TYPE"PLUMBING"
CDS_LIB"mstr_standard";
"B \NAC \NWC"3;
"S \NAC"
BN"15"119;
%"TAP"
"6","(-3100,4750)","0","mstr_standard","I115";
;
HDL_TAP"TRUE"
BODY_TYPE"PLUMBING"
CDS_LIB"mstr_standard";
"B \NAC \NWC"3;
"S \NAC"
BN"14"120;
%"TAP"
"6","(-3100,4700)","0","mstr_standard","I116";
;
HDL_TAP"TRUE"
BODY_TYPE"PLUMBING"
CDS_LIB"mstr_standard";
"B \NAC \NWC"3;
"S \NAC"
BN"13"121;
%"TAP"
"6","(-3100,4650)","0","mstr_standard","I117";
;
HDL_TAP"TRUE"
BODY_TYPE"PLUMBING"
CDS_LIB"mstr_standard";
"B \NAC \NWC"3;
"S \NAC"
BN"12"122;
%"TAP"
"6","(-3100,4600)","0","mstr_standard","I118";
;
HDL_TAP"TRUE"
BODY_TYPE"PLUMBING"
CDS_LIB"mstr_standard";
"B \NAC \NWC"3;
"S \NAC"
BN"11"113;
%"TAP"
"6","(-3100,4550)","0","mstr_standard","I119";
;
HDL_TAP"TRUE"
BODY_TYPE"PLUMBING"
CDS_LIB"mstr_standard";
"B \NAC \NWC"3;
"S \NAC"
BN"10"114;
%"TAP"
"6","(700,4850)","2","mstr_standard","I12";
;
HDL_TAP"TRUE"
BODY_TYPE"PLUMBING"
CDS_LIB"mstr_standard";
"B \NAC \NWC"2;
"S \NAC"
BN"14"166;
%"TAP"
"6","(-3100,4500)","0","mstr_standard","I120";
;
HDL_TAP"TRUE"
BODY_TYPE"PLUMBING"
CDS_LIB"mstr_standard";
"B \NAC \NWC"3;
"S \NAC"
BN"9"115;
%"TAP"
"6","(-3100,4450)","0","mstr_standard","I121";
;
HDL_TAP"TRUE"
BODY_TYPE"PLUMBING"
CDS_LIB"mstr_standard";
"B \NAC \NWC"3;
"S \NAC"
BN"8"116;
%"TAP"
"6","(-3100,4400)","0","mstr_standard","I122";
;
HDL_TAP"TRUE"
BODY_TYPE"PLUMBING"
CDS_LIB"mstr_standard";
"B \NAC \NWC"3;
"S \NAC"
BN"7"117;
%"TAP"
"6","(-3100,4350)","0","mstr_standard","I123";
;
HDL_TAP"TRUE"
BODY_TYPE"PLUMBING"
CDS_LIB"mstr_standard";
"B \NAC \NWC"3;
"S \NAC"
BN"6"108;
%"TAP"
"6","(-3100,4300)","0","mstr_standard","I124";
;
HDL_TAP"TRUE"
BODY_TYPE"PLUMBING"
CDS_LIB"mstr_standard";
"B \NAC \NWC"3;
"S \NAC"
BN"5"109;
%"TAP"
"6","(-3100,4250)","0","mstr_standard","I125";
;
HDL_TAP"TRUE"
BODY_TYPE"PLUMBING"
CDS_LIB"mstr_standard";
"B \NAC \NWC"3;
"S \NAC"
BN"4"110;
%"TAP"
"6","(-3100,4200)","0","mstr_standard","I126";
;
HDL_TAP"TRUE"
BODY_TYPE"PLUMBING"
CDS_LIB"mstr_standard";
"B \NAC \NWC"3;
"S \NAC"
BN"3"111;
%"TAP"
"6","(-3100,4150)","0","mstr_standard","I127";
;
HDL_TAP"TRUE"
BODY_TYPE"PLUMBING"
CDS_LIB"mstr_standard";
"B \NAC \NWC"3;
"S \NAC"
BN"2"107;
%"TAP"
"6","(-3100,4100)","0","mstr_standard","I128";
;
HDL_TAP"TRUE"
BODY_TYPE"PLUMBING"
CDS_LIB"mstr_standard";
"B \NAC \NWC"3;
"S \NAC"
BN"1"112;
%"TAP"
"6","(-3100,4050)","0","mstr_standard","I129";
;
HDL_TAP"TRUE"
BODY_TYPE"PLUMBING"
CDS_LIB"mstr_standard";
"B \NAC \NWC"3;
"S \NAC"
BN"0"58;
%"TAP"
"6","(700,4750)","2","mstr_standard","I13";
;
HDL_TAP"TRUE"
BODY_TYPE"PLUMBING"
CDS_LIB"mstr_standard";
"B \NAC \NWC"2;
"S \NAC"
BN"13"168;
%"TAP"
"6","(-3100,3950)","0","mstr_standard","I130";
;
HDL_TAP"TRUE"
BODY_TYPE"PLUMBING"
CDS_LIB"mstr_standard";
"B \NAC \NWC"6;
"S \NAC"
BN"1"59;
%"TAP"
"6","(-3100,3900)","0","mstr_standard","I133";
;
HDL_TAP"TRUE"
BODY_TYPE"PLUMBING"
CDS_LIB"mstr_standard";
"B \NAC \NWC"6;
"S \NAC"
BN"0"56;
%"TAP"
"6","(-3100,3850)","0","mstr_standard","I134";
;
HDL_TAP"TRUE"
BODY_TYPE"PLUMBING"
CDS_LIB"mstr_standard";
"B \NAC \NWC"5;
"S \NAC"
BN"1"57;
%"TAP"
"6","(-3100,3800)","0","mstr_standard","I135";
;
HDL_TAP"TRUE"
BODY_TYPE"PLUMBING"
CDS_LIB"mstr_standard";
"B \NAC \NWC"5;
"S \NAC"
BN"0"55;
%"TAP"
"6","(-3100,2800)","0","mstr_standard","I138";
;
HDL_TAP"TRUE"
BODY_TYPE"PLUMBING"
CDS_LIB"mstr_standard";
"B \NAC \NWC"9;
"S \NAC"
BN"7"46;
%"TAP"
"6","(-3100,2850)","0","mstr_standard","I139";
;
HDL_TAP"TRUE"
BODY_TYPE"PLUMBING"
CDS_LIB"mstr_standard";
"B \NAC \NWC"9;
"S \NAC"
BN"6"49;
%"TAP"
"6","(700,4550)","2","mstr_standard","I14";
;
HDL_TAP"TRUE"
BODY_TYPE"PLUMBING"
CDS_LIB"mstr_standard";
"B \NAC \NWC"2;
"S \NAC"
BN"11"172;
%"TAP"
"6","(-3100,2750)","0","mstr_standard","I140";
;
HDL_TAP"TRUE"
BODY_TYPE"PLUMBING"
CDS_LIB"mstr_standard";
"B \NAC \NWC"9;
"S \NAC"
BN"4"45;
%"TAP"
"6","(-3100,2700)","0","mstr_standard","I141";
;
HDL_TAP"TRUE"
BODY_TYPE"PLUMBING"
CDS_LIB"mstr_standard";
"B \NAC \NWC"9;
"S \NAC"
BN"5"44;
%"TAP"
"6","(-3100,2650)","0","mstr_standard","I142";
;
HDL_TAP"TRUE"
BODY_TYPE"PLUMBING"
CDS_LIB"mstr_standard";
"B \NAC \NWC"9;
"S \NAC"
BN"2"43;
%"TAP"
"6","(-3100,2600)","0","mstr_standard","I143";
;
HDL_TAP"TRUE"
BODY_TYPE"PLUMBING"
CDS_LIB"mstr_standard";
"B \NAC \NWC"9;
"S \NAC"
BN"3"42;
%"TAP"
"6","(-3100,2550)","0","mstr_standard","I144";
;
HDL_TAP"TRUE"
BODY_TYPE"PLUMBING"
CDS_LIB"mstr_standard";
"B \NAC \NWC"9;
"S \NAC"
BN"0"41;
%"TAP"
"6","(-3100,2500)","0","mstr_standard","I145";
;
HDL_TAP"TRUE"
BODY_TYPE"PLUMBING"
CDS_LIB"mstr_standard";
"B \NAC \NWC"9;
"S \NAC"
BN"1"40;
%"TAP"
"6","(700,4650)","2","mstr_standard","I15";
;
HDL_TAP"TRUE"
BODY_TYPE"PLUMBING"
CDS_LIB"mstr_standard";
"B \NAC \NWC"2;
"S \NAC"
BN"12"170;
%"TAP"
"6","(-3500,3600)","0","mstr_standard","I152";
;
HDL_TAP"TRUE"
BODY_TYPE"PLUMBING"
CDS_LIB"mstr_standard";
"B \NAC \NWC"11;
"S \NAC"
BN"0"35;
%"TAP"
"6","(-3650,3550)","0","mstr_standard","I153";
;
HDL_TAP"TRUE"
BODY_TYPE"PLUMBING"
CDS_LIB"mstr_standard";
"B \NAC \NWC"10;
"S \NAC"
BN"0"36;
%"TAP"
"6","(-3100,3400)","0","mstr_standard","I156";
;
HDL_TAP"TRUE"
BODY_TYPE"PLUMBING"
CDS_LIB"mstr_standard";
"B \NAC \NWC"7;
"S \NAC"
BN"3"54;
%"TAP"
"6","(-3100,3350)","0","mstr_standard","I157";
;
HDL_TAP"TRUE"
BODY_TYPE"PLUMBING"
CDS_LIB"mstr_standard";
"B \NAC \NWC"7;
"S \NAC"
BN"2"53;
%"TAP"
"6","(-3100,3300)","0","mstr_standard","I158";
;
HDL_TAP"TRUE"
BODY_TYPE"PLUMBING"
CDS_LIB"mstr_standard";
"B \NAC \NWC"7;
"S \NAC"
BN"1"51;
%"TAP"
"6","(-3100,3250)","0","mstr_standard","I159";
;
HDL_TAP"TRUE"
BODY_TYPE"PLUMBING"
CDS_LIB"mstr_standard";
"B \NAC \NWC"7;
"S \NAC"
BN"0"50;
%"PVDDQ_DEF"
"1","(-1225,2600)","0","mstr_symbols","I16";
;
HDL_POWER"PVDDQ_DEF"
ROOM"DDR4_CH_B"
BODY_TYPE"PLUMBING"
CDS_LIB"mstr_symbols"
BOM_COST"MEM"
VOLTAGE"1.2V";
"G\NAC"13;
%"TAP"
"6","(-3150,3150)","0","mstr_standard","I160";
;
HDL_TAP"TRUE"
BODY_TYPE"PLUMBING"
CDS_LIB"mstr_standard";
"B \NAC \NWC"12;
"S \NAC"
BN"1"34;
%"TAP"
"6","(-3150,3100)","0","mstr_standard","I163";
;
HDL_TAP"TRUE"
BODY_TYPE"PLUMBING"
CDS_LIB"mstr_standard";
"B \NAC \NWC"12;
"S \NAC"
BN"0"32;
%"TAP"
"6","(-3100,3000)","0","mstr_standard","I164";
;
HDL_TAP"TRUE"
BODY_TYPE"PLUMBING"
CDS_LIB"mstr_standard";
"B \NAC \NWC"8;
"S \NAC"
BN"1"47;
%"TAP"
"6","(-3100,2950)","0","mstr_standard","I166";
;
HDL_TAP"TRUE"
BODY_TYPE"PLUMBING"
CDS_LIB"mstr_standard";
"B \NAC \NWC"8;
"S \NAC"
BN"0"48;
%"SCONN288_H44441004"
"4","(-150,2050)","0","mstr_sconn","I167";
;
CDS_SEC"4"
ROOM"DDR4_CH_E"
CDS_LOCATION"J4A2"
SEC"4"
SEC_TYPE"PIP"
CDS_LIB"mstr_sconn"
BOM_COST"MEM"
PACK_TYPE"PIP"
MATERIAL"SCONN"
PART_NUMBER"H44441-004"
LOCATION"J4A2";
"VPP<4>"
$PN"142"18;
"VTT<1>"
$PN"77"15;
"VPP<0>"
$PN"287"18;
"VPP<1>"
$PN"286"18;
"VPP<2>"
$PN"288"18;
"VPP<3>"
$PN"143"18;
"VDD<1>"
$PN"233"13;
"VDD<2>"
$PN"231"13;
"VDD<3>"
$PN"229"13;
"VDD<4>"
$PN"226"13;
"VDD<5>"
$PN"223"13;
"VDD<7>"
$PN"217"13;
"VDD<8>"
$PN"215"13;
"VDD<9>"
$PN"212"13;
"VDD<11>"
$PN"206"13;
"VDD<12>"
$PN"204"13;
"VDD<14>"
$PN"90"13;
"VDD<15>"
$PN"88"13;
"VDD<17>"
$PN"83"13;
"VDD<18>"
$PN"80"13;
"VDD<20>"
$PN"73"13;
"VDD<21>"
$PN"70"13;
"VDD<22>"
$PN"67"13;
"VDD<24>"
$PN"61"13;
"12V<0>"
$PN"145"20;
"12V<1>"
$PN"1"20;
"VTT<0>"
$PN"221"15;
"VDD<25>"
$PN"59"13;
"VDD<23>"
$PN"64"13;
"VDD<19>"
$PN"76"13;
"VDD<16>"
$PN"85"13;
"VDD<13>"
$PN"92"13;
"VDD<10>"
$PN"209"13;
"VDD<6>"
$PN"220"13;
"VDD<0>"
$PN"236"13;
%"GND"
"1","(2500,1200)","2","mstr_symbols","I168";
;
HDL_POWER"GND"
ROOM"DDR4_CH_B"
BODY_TYPE"PLUMBING"
BOM_COST"MEM"
CDS_LIB"mstr_symbols"
SIZE"1B"
VOLTAGE"0";
"A\NAC"14;
%"PVTT_DEF"
"1","(-1000,2750)","0","mstr_symbols","I17";
;
HDL_POWER"PVTT_DEF"
ROOM"DDR4_CH_B"
BODY_TYPE"PLUMBING"
CDS_LIB"mstr_symbols"
BOM_COST"MEM"
VOLTAGE"0.6V";
"G\NAC"15;
%"GND"
"1","(-5200,1800)","2","mstr_symbols","I174";
;
HDL_POWER"GND"
ROOM"DDR4_CH_B"
BODY_TYPE"PLUMBING"
BOM_COST"MEM"
CDS_LIB"mstr_symbols"
SIZE"1B"
VOLTAGE"0";
"A\NAC"16;
%"CAP_A"
"1","(-4650,1550)","2","dev_discrete","I175";
;
ROOM"DDR4_CH_E"
$SEC"1"
CDS_SEC"1"
CDS_LIB"dev_discrete"
BOM_COST"MEM"
CDS_LOCATION"C6L6"
MATERIAL"X7R"
VOLTAGE"25V"
PACK_TYPE"0402V"
TOLERANCE"10%"
VALUE"0.01UF"
PART_NUMBER"A36096-045"
LOCATION"C6L6";
"B"
$PN"2"17;
"A"
$PN"1"22;
%"GND"
"1","(-4650,1300)","2","mstr_symbols","I176";
;
HDL_POWER"GND"
ROOM"DDR4_CH_B"
BODY_TYPE"PLUMBING"
SIZE"1B"
CDS_LIB"mstr_symbols"
BOM_COST"MEM"
VOLTAGE"0";
"A\NAC"17;
%"PVPP_DEF"
"1","(-850,3050)","0","mstr_symbols","I177";
;
HDL_POWER"PVPP_DEF"
ROOM"DDR4_CH_B"
BODY_TYPE"PLUMBING"
CDS_LIB"mstr_symbols"
BOM_COST"MEM"
VOLTAGE"2.5V";
"G\NAC"18;
%"PVPP_DEF"
"1","(-5200,2250)","0","mstr_symbols","I178";
;
HDL_POWER"PVPP_DEF"
ROOM"DDR4_CH_B"
BODY_TYPE"PLUMBING"
CDS_LIB"mstr_symbols"
BOM_COST"MEM"
VOLTAGE"2.5V";
"G\NAC"19;
%"TAP"
"6","(-3500,3700)","0","mstr_standard","I183";
;
HDL_TAP"TRUE"
BODY_TYPE"PLUMBING"
CDS_LIB"mstr_standard";
"B \NAC \NWC"11;
"S \NAC"
BN"1"33;
%"TAP"
"6","(-3650,3650)","0","mstr_standard","I184";
;
HDL_TAP"TRUE"
BODY_TYPE"PLUMBING"
CDS_LIB"mstr_standard";
"B \NAC \NWC"10;
"S \NAC"
BN"1"37;
%"P12V_NVDIMM_DEF"
"1","(550,3125)","0","mstr_symbols","I185";
;
HDL_POWER"P12V_NVDIMM_DEF"
BODY_TYPE"PLUMBING"
CDS_LIB"mstr_symbols"
VOLTAGE"12.0";
"G\NAC"20;
%"TAP"
"6","(900,4500)","2","mstr_standard","I19";
;
HDL_TAP"TRUE"
BODY_TYPE"PLUMBING"
CDS_LIB"mstr_standard";
"B \NAC \NWC"1;
"S \NAC"
BN"11"173;
%"TAP"
"6","(900,4400)","2","mstr_standard","I20";
;
HDL_TAP"TRUE"
BODY_TYPE"PLUMBING"
CDS_LIB"mstr_standard";
"B \NAC \NWC"1;
"S \NAC"
BN"10"175;
%"TAP"
"6","(900,4300)","2","mstr_standard","I21";
;
HDL_TAP"TRUE"
BODY_TYPE"PLUMBING"
CDS_LIB"mstr_standard";
"B \NAC \NWC"1;
"S \NAC"
BN"9"156;
%"TAP"
"6","(900,4200)","2","mstr_standard","I22";
;
HDL_TAP"TRUE"
BODY_TYPE"PLUMBING"
CDS_LIB"mstr_standard";
"B \NAC \NWC"1;
"S \NAC"
BN"8"158;
%"TAP"
"6","(900,4100)","2","mstr_standard","I23";
;
HDL_TAP"TRUE"
BODY_TYPE"PLUMBING"
CDS_LIB"mstr_standard";
"B \NAC \NWC"1;
"S \NAC"
BN"7"160;
%"TAP"
"6","(700,4350)","2","mstr_standard","I24";
;
HDL_TAP"TRUE"
BODY_TYPE"PLUMBING"
CDS_LIB"mstr_standard";
"B \NAC \NWC"2;
"S \NAC"
BN"9"155;
%"TAP"
"6","(700,4450)","2","mstr_standard","I25";
;
HDL_TAP"TRUE"
BODY_TYPE"PLUMBING"
CDS_LIB"mstr_standard";
"B \NAC \NWC"2;
"S \NAC"
BN"10"174;
%"TAP"
"6","(700,4250)","2","mstr_standard","I26";
;
HDL_TAP"TRUE"
BODY_TYPE"PLUMBING"
CDS_LIB"mstr_standard";
"B \NAC \NWC"2;
"S \NAC"
BN"8"157;
%"TAP"
"6","(700,4050)","2","mstr_standard","I27";
;
HDL_TAP"TRUE"
BODY_TYPE"PLUMBING"
CDS_LIB"mstr_standard";
"B \NAC \NWC"2;
"S \NAC"
BN"6"141;
%"TAP"
"6","(700,4150)","2","mstr_standard","I28";
;
HDL_TAP"TRUE"
BODY_TYPE"PLUMBING"
CDS_LIB"mstr_standard";
"B \NAC \NWC"2;
"S \NAC"
BN"7"159;
%"TAP"
"6","(900,4000)","2","mstr_standard","I29";
;
HDL_TAP"TRUE"
BODY_TYPE"PLUMBING"
CDS_LIB"mstr_standard";
"B \NAC \NWC"1;
"S \NAC"
BN"6"142;
%"TAP"
"6","(900,5100)","2","mstr_standard","I3";
;
HDL_TAP"TRUE"
BODY_TYPE"PLUMBING"
CDS_LIB"mstr_standard";
"B \NAC \NWC"1;
"S \NAC"
BN"17"161;
%"TAP"
"6","(900,3900)","2","mstr_standard","I30";
;
HDL_TAP"TRUE"
BODY_TYPE"PLUMBING"
CDS_LIB"mstr_standard";
"B \NAC \NWC"1;
"S \NAC"
BN"5"144;
%"TAP"
"6","(900,3800)","2","mstr_standard","I31";
;
HDL_TAP"TRUE"
BODY_TYPE"PLUMBING"
CDS_LIB"mstr_standard";
"B \NAC \NWC"1;
"S \NAC"
BN"4"146;
%"TAP"
"6","(900,3700)","2","mstr_standard","I32";
;
HDL_TAP"TRUE"
BODY_TYPE"PLUMBING"
CDS_LIB"mstr_standard";
"B \NAC \NWC"1;
"S \NAC"
BN"3"148;
%"TAP"
"6","(900,3600)","2","mstr_standard","I33";
;
HDL_TAP"TRUE"
BODY_TYPE"PLUMBING"
CDS_LIB"mstr_standard";
"B \NAC \NWC"1;
"S \NAC"
BN"2"150;
%"TAP"
"6","(700,3850)","2","mstr_standard","I34";
;
HDL_TAP"TRUE"
BODY_TYPE"PLUMBING"
CDS_LIB"mstr_standard";
"B \NAC \NWC"2;
"S \NAC"
BN"4"145;
%"TAP"
"6","(700,3950)","2","mstr_standard","I35";
;
HDL_TAP"TRUE"
BODY_TYPE"PLUMBING"
CDS_LIB"mstr_standard";
"B \NAC \NWC"2;
"S \NAC"
BN"5"143;
%"TAP"
"6","(700,3750)","2","mstr_standard","I36";
;
HDL_TAP"TRUE"
BODY_TYPE"PLUMBING"
CDS_LIB"mstr_standard";
"B \NAC \NWC"2;
"S \NAC"
BN"3"147;
%"TAP"
"6","(700,3650)","2","mstr_standard","I37";
;
HDL_TAP"TRUE"
BODY_TYPE"PLUMBING"
CDS_LIB"mstr_standard";
"B \NAC \NWC"2;
"S \NAC"
BN"2"149;
%"TAP"
"6","(700,3550)","2","mstr_standard","I38";
;
HDL_TAP"TRUE"
BODY_TYPE"PLUMBING"
CDS_LIB"mstr_standard";
"B \NAC \NWC"2;
"S \NAC"
BN"1"151;
%"TAP"
"6","(900,3400)","2","mstr_standard","I39";
;
HDL_TAP"TRUE"
BODY_TYPE"PLUMBING"
CDS_LIB"mstr_standard";
"B \NAC \NWC"1;
"S \NAC"
BN"0"154;
%"TAP"
"6","(700,5150)","2","mstr_standard","I4";
;
HDL_TAP"TRUE"
BODY_TYPE"PLUMBING"
CDS_LIB"mstr_standard";
"B \NAC \NWC"2;
"S \NAC"
BN"17"176;
%"TAP"
"6","(900,3500)","2","mstr_standard","I40";
;
HDL_TAP"TRUE"
BODY_TYPE"PLUMBING"
CDS_LIB"mstr_standard";
"B \NAC \NWC"1;
"S \NAC"
BN"1"152;
%"TAP"
"6","(700,3450)","2","mstr_standard","I41";
;
HDL_TAP"TRUE"
BODY_TYPE"PLUMBING"
CDS_LIB"mstr_standard";
"B \NAC \NWC"2;
"S \NAC"
BN"0"153;
%"SCONN288_H44441004"
"3","(1800,2500)","0","mstr_sconn","I43";
;
CDS_SEC"3"
ROOM"DDR4_CH_E"
CDS_LOCATION"J4A2"
SEC"3"
SEC_TYPE"PIP"
CDS_LIB"mstr_sconn"
BOM_COST"MEM"
PACK_TYPE"PIP"
MATERIAL"SCONN"
PART_NUMBER"H44441-004"
LOCATION"J4A2";
"VSS<93>"
$PN"2"21;
"VSS<92>"
$PN"4"21;
"VSS<91>"
$PN"6"21;
"VSS<90>"
$PN"9"21;
"VSS<89>"
$PN"11"21;
"VSS<88>"
$PN"13"21;
"VSS<0>"
$PN"283"14;
"VSS<1>"
$PN"281"14;
"VSS<2>"
$PN"279"14;
"VSS<3>"
$PN"276"14;
"VSS<4>"
$PN"274"14;
"VSS<5>"
$PN"272"14;
"VSS<6>"
$PN"270"14;
"VSS<7>"
$PN"268"14;
"VSS<8>"
$PN"265"14;
"VSS<9>"
$PN"263"14;
"VSS<10>"
$PN"261"14;
"VSS<11>"
$PN"259"14;
"VSS<12>"
$PN"257"14;
"VSS<13>"
$PN"254"14;
"VSS<14>"
$PN"252"14;
"VSS<15>"
$PN"250"14;
"VSS<16>"
$PN"248"14;
"VSS<17>"
$PN"246"14;
"VSS<18>"
$PN"243"14;
"VSS<19>"
$PN"241"14;
"VSS<20>"
$PN"239"14;
"VSS<21>"
$PN"202"14;
"VSS<22>"
$PN"200"14;
"VSS<23>"
$PN"198"14;
"VSS<24>"
$PN"195"14;
"VSS<25>"
$PN"193"14;
"VSS<26>"
$PN"191"14;
"VSS<27>"
$PN"189"14;
"VSS<28>"
$PN"187"14;
"VSS<29>"
$PN"184"14;
"VSS<30>"
$PN"182"14;
"VSS<31>"
$PN"180"14;
"VSS<32>"
$PN"178"14;
"VSS<33>"
$PN"176"14;
"VSS<34>"
$PN"173"14;
"VSS<35>"
$PN"171"14;
"VSS<36>"
$PN"169"14;
"VSS<37>"
$PN"167"14;
"VSS<38>"
$PN"165"14;
"VSS<39>"
$PN"162"14;
"VSS<40>"
$PN"160"14;
"VSS<41>"
$PN"158"14;
"VSS<42>"
$PN"156"14;
"VSS<43>"
$PN"154"14;
"VSS<44>"
$PN"151"14;
"VSS<47>"
$PN"138"21;
"VSS<48>"
$PN"136"21;
"VSS<49>"
$PN"134"21;
"VSS<50>"
$PN"131"21;
"VSS<51>"
$PN"129"21;
"VSS<52>"
$PN"127"21;
"VSS<53>"
$PN"125"21;
"VSS<54>"
$PN"123"21;
"VSS<55>"
$PN"120"21;
"VSS<56>"
$PN"118"21;
"VSS<57>"
$PN"116"21;
"VSS<58>"
$PN"114"21;
"VSS<59>"
$PN"112"21;
"VSS<60>"
$PN"109"21;
"VSS<61>"
$PN"107"21;
"VSS<62>"
$PN"105"21;
"VSS<63>"
$PN"103"21;
"VSS<64>"
$PN"101"21;
"VSS<65>"
$PN"98"21;
"VSS<66>"
$PN"96"21;
"VSS<67>"
$PN"94"21;
"VSS<68>"
$PN"57"21;
"VSS<69>"
$PN"55"21;
"VSS<70>"
$PN"53"21;
"VSS<71>"
$PN"50"21;
"VSS<72>"
$PN"48"21;
"VSS<73>"
$PN"46"21;
"VSS<74>"
$PN"44"21;
"VSS<75>"
$PN"42"21;
"VSS<76>"
$PN"39"21;
"VSS<77>"
$PN"37"21;
"VSS<78>"
$PN"35"21;
"VSS<79>"
$PN"33"21;
"VSS<80>"
$PN"31"21;
"VSS<81>"
$PN"28"21;
"VSS<82>"
$PN"26"21;
"VSS<83>"
$PN"24"21;
"VSS<84>"
$PN"22"21;
"VSS<85>"
$PN"20"21;
"VSS<86>"
$PN"17"21;
"VSS<87>"
$PN"15"21;
"VSS<45>"
$PN"149"14;
"VSS<46>"
$PN"147"14;
%"GND"
"1","(1100,1200)","2","mstr_symbols","I44";
;
HDL_POWER"GND"
ROOM"DDR4_CH_B"
BODY_TYPE"PLUMBING"
BOM_COST"MEM"
CDS_LIB"mstr_symbols"
SIZE"1B"
VOLTAGE"0";
"A\NAC"21;
%"TAP"
"6","(-1600,4900)","2","mstr_standard","I46";
;
HDL_TAP"TRUE"
BODY_TYPE"PLUMBING"
CDS_LIB"mstr_standard";
"B \NAC \NWC"4;
"S \NAC"
BN"62"135;
%"TAP"
"6","(-1600,4850)","2","mstr_standard","I47";
;
HDL_TAP"TRUE"
BODY_TYPE"PLUMBING"
CDS_LIB"mstr_standard";
"B \NAC \NWC"4;
"S \NAC"
BN"63"136;
%"TAP"
"6","(-1600,4750)","2","mstr_standard","I48";
;
HDL_TAP"TRUE"
BODY_TYPE"PLUMBING"
CDS_LIB"mstr_standard";
"B \NAC \NWC"4;
"S \NAC"
BN"61"140;
%"TAP"
"6","(-1600,4800)","2","mstr_standard","I49";
;
HDL_TAP"TRUE"
BODY_TYPE"PLUMBING"
CDS_LIB"mstr_standard";
"B \NAC \NWC"4;
"S \NAC"
BN"60"137;
%"TAP"
"6","(900,5000)","2","mstr_standard","I5";
;
HDL_TAP"TRUE"
BODY_TYPE"PLUMBING"
CDS_LIB"mstr_standard";
"B \NAC \NWC"1;
"S \NAC"
BN"16"163;
%"TAP"
"6","(-1600,4700)","2","mstr_standard","I50";
;
HDL_TAP"TRUE"
BODY_TYPE"PLUMBING"
CDS_LIB"mstr_standard";
"B \NAC \NWC"4;
"S \NAC"
BN"58"139;
%"TAP"
"6","(-1600,4600)","2","mstr_standard","I51";
;
HDL_TAP"TRUE"
BODY_TYPE"PLUMBING"
CDS_LIB"mstr_standard";
"B \NAC \NWC"4;
"S \NAC"
BN"56"132;
%"TAP"
"6","(-1600,4650)","2","mstr_standard","I52";
;
HDL_TAP"TRUE"
BODY_TYPE"PLUMBING"
CDS_LIB"mstr_standard";
"B \NAC \NWC"4;
"S \NAC"
BN"59"138;
%"TAP"
"6","(-1600,4550)","2","mstr_standard","I53";
;
HDL_TAP"TRUE"
BODY_TYPE"PLUMBING"
CDS_LIB"mstr_standard";
"B \NAC \NWC"4;
"S \NAC"
BN"57"134;
%"TAP"
"6","(-1600,4500)","2","mstr_standard","I54";
;
HDL_TAP"TRUE"
BODY_TYPE"PLUMBING"
CDS_LIB"mstr_standard";
"B \NAC \NWC"4;
"S \NAC"
BN"54"133;
%"TAP"
"6","(-1600,4400)","2","mstr_standard","I55";
;
HDL_TAP"TRUE"
BODY_TYPE"PLUMBING"
CDS_LIB"mstr_standard";
"B \NAC \NWC"4;
"S \NAC"
BN"52"130;
%"TAP"
"6","(-1600,4450)","2","mstr_standard","I56";
;
HDL_TAP"TRUE"
BODY_TYPE"PLUMBING"
CDS_LIB"mstr_standard";
"B \NAC \NWC"4;
"S \NAC"
BN"55"131;
%"TAP"
"6","(-1600,4350)","2","mstr_standard","I57";
;
HDL_TAP"TRUE"
BODY_TYPE"PLUMBING"
CDS_LIB"mstr_standard";
"B \NAC \NWC"4;
"S \NAC"
BN"53"129;
%"TAP"
"6","(-1600,4300)","2","mstr_standard","I58";
;
HDL_TAP"TRUE"
BODY_TYPE"PLUMBING"
CDS_LIB"mstr_standard";
"B \NAC \NWC"4;
"S \NAC"
BN"50"128;
%"TAP"
"6","(-1600,4250)","2","mstr_standard","I59";
;
HDL_TAP"TRUE"
BODY_TYPE"PLUMBING"
CDS_LIB"mstr_standard";
"B \NAC \NWC"4;
"S \NAC"
BN"51"127;
%"TAP"
"6","(900,4900)","2","mstr_standard","I6";
;
HDL_TAP"TRUE"
BODY_TYPE"PLUMBING"
CDS_LIB"mstr_standard";
"B \NAC \NWC"1;
"S \NAC"
BN"15"165;
%"TAP"
"6","(-1600,4200)","2","mstr_standard","I60";
;
HDL_TAP"TRUE"
BODY_TYPE"PLUMBING"
CDS_LIB"mstr_standard";
"B \NAC \NWC"4;
"S \NAC"
BN"48"126;
%"TAP"
"6","(-1600,4100)","2","mstr_standard","I61";
;
HDL_TAP"TRUE"
BODY_TYPE"PLUMBING"
CDS_LIB"mstr_standard";
"B \NAC \NWC"4;
"S \NAC"
BN"46"124;
%"TAP"
"6","(-1600,4150)","2","mstr_standard","I62";
;
HDL_TAP"TRUE"
BODY_TYPE"PLUMBING"
CDS_LIB"mstr_standard";
"B \NAC \NWC"4;
"S \NAC"
BN"49"125;
%"TAP"
"6","(-1600,4050)","2","mstr_standard","I63";
;
HDL_TAP"TRUE"
BODY_TYPE"PLUMBING"
CDS_LIB"mstr_standard";
"B \NAC \NWC"4;
"S \NAC"
BN"47"106;
%"TAP"
"6","(-1600,4000)","2","mstr_standard","I64";
;
HDL_TAP"TRUE"
BODY_TYPE"PLUMBING"
CDS_LIB"mstr_standard";
"B \NAC \NWC"4;
"S \NAC"
BN"44"105;
%"TAP"
"6","(-1600,3950)","2","mstr_standard","I65";
;
HDL_TAP"TRUE"
BODY_TYPE"PLUMBING"
CDS_LIB"mstr_standard";
"B \NAC \NWC"4;
"S \NAC"
BN"45"104;
%"SCONN288_H44441004"
"2","(0,4300)","0","mstr_sconn","I66";
;
CDS_SEC"2"
ROOM"DDR4_CH_E"
CDS_LOCATION"J4A2"
SEC"2"
SEC_TYPE"PIP"
CDS_LIB"mstr_sconn"
BOM_COST"MEM"
PACK_TYPE"PIP"
MATERIAL"SCONN"
PART_NUMBER"H44441-004"
LOCATION"J4A2";
"DQS17P"
$PN"51"176;
"DQS9P"
$PN"7"155;
"DQS9N"
$PN"8"156;
"DQS8P"
$PN"197"157;
"DQS8N"
$PN"196"158;
"DQS7P"
$PN"278"159;
"DQS7N"
$PN"277"160;
"DQS6P"
$PN"267"141;
"DQS6N"
$PN"266"142;
"DQS5P"
$PN"256"143;
"DQS5N"
$PN"255"144;
"DQS4P"
$PN"245"145;
"DQS4N"
$PN"244"146;
"DQS3P"
$PN"186"147;
"DQS3N"
$PN"185"148;
"DQS2P"
$PN"175"149;
"DQS2N"
$PN"174"150;
"DQS1P"
$PN"164"151;
"DQS1N"
$PN"163"152;
"DQS17N"
$PN"52"161;
"DQS16P"
$PN"132"162;
"DQS16N"
$PN"133"163;
"DQS15P"
$PN"121"164;
"DQS15N"
$PN"122"165;
"DQS14P"
$PN"110"166;
"DQS14N"
$PN"111"167;
"DQS13P"
$PN"99"168;
"DQS13N"
$PN"100"169;
"DQS12P"
$PN"40"170;
"DQS12N"
$PN"41"171;
"DQS11P"
$PN"29"172;
"DQS11N"
$PN"30"173;
"DQS10P"
$PN"18"174;
"DQS10N"
$PN"19"175;
"DQS0P"
$PN"153"153;
"DQS0N"
$PN"152"154;
%"TAP"
"6","(-1600,3900)","2","mstr_standard","I67";
;
HDL_TAP"TRUE"
BODY_TYPE"PLUMBING"
CDS_LIB"mstr_standard";
"B \NAC \NWC"4;
"S \NAC"
BN"42"103;
%"TAP"
"6","(-1600,3850)","2","mstr_standard","I68";
;
HDL_TAP"TRUE"
BODY_TYPE"PLUMBING"
CDS_LIB"mstr_standard";
"B \NAC \NWC"4;
"S \NAC"
BN"43"102;
%"TAP"
"6","(-1600,3750)","2","mstr_standard","I69";
;
HDL_TAP"TRUE"
BODY_TYPE"PLUMBING"
CDS_LIB"mstr_standard";
"B \NAC \NWC"4;
"S \NAC"
BN"41"100;
%"TAP"
"6","(900,4700)","2","mstr_standard","I7";
;
HDL_TAP"TRUE"
BODY_TYPE"PLUMBING"
CDS_LIB"mstr_standard";
"B \NAC \NWC"1;
"S \NAC"
BN"13"169;
%"TAP"
"6","(-1600,3700)","2","mstr_standard","I70";
;
HDL_TAP"TRUE"
BODY_TYPE"PLUMBING"
CDS_LIB"mstr_standard";
"B \NAC \NWC"4;
"S \NAC"
BN"38"99;
%"TAP"
"6","(-1600,3800)","2","mstr_standard","I71";
;
HDL_TAP"TRUE"
BODY_TYPE"PLUMBING"
CDS_LIB"mstr_standard";
"B \NAC \NWC"4;
"S \NAC"
BN"40"101;
%"TAP"
"6","(-1600,3650)","2","mstr_standard","I72";
;
HDL_TAP"TRUE"
BODY_TYPE"PLUMBING"
CDS_LIB"mstr_standard";
"B \NAC \NWC"4;
"S \NAC"
BN"39"97;
%"TAP"
"6","(-1600,3600)","2","mstr_standard","I73";
;
HDL_TAP"TRUE"
BODY_TYPE"PLUMBING"
CDS_LIB"mstr_standard";
"B \NAC \NWC"4;
"S \NAC"
BN"36"98;
%"TAP"
"6","(-1600,3550)","2","mstr_standard","I74";
;
HDL_TAP"TRUE"
BODY_TYPE"PLUMBING"
CDS_LIB"mstr_standard";
"B \NAC \NWC"4;
"S \NAC"
BN"37"88;
%"TAP"
"6","(-1600,3450)","2","mstr_standard","I75";
;
HDL_TAP"TRUE"
BODY_TYPE"PLUMBING"
CDS_LIB"mstr_standard";
"B \NAC \NWC"4;
"S \NAC"
BN"35"94;
%"TAP"
"6","(-1600,3500)","2","mstr_standard","I76";
;
HDL_TAP"TRUE"
BODY_TYPE"PLUMBING"
CDS_LIB"mstr_standard";
"B \NAC \NWC"4;
"S \NAC"
BN"34"89;
%"TAP"
"6","(-1600,3400)","2","mstr_standard","I77";
;
HDL_TAP"TRUE"
BODY_TYPE"PLUMBING"
CDS_LIB"mstr_standard";
"B \NAC \NWC"4;
"S \NAC"
BN"32"93;
%"TAP"
"6","(-1600,3350)","2","mstr_standard","I78";
;
HDL_TAP"TRUE"
BODY_TYPE"PLUMBING"
CDS_LIB"mstr_standard";
"B \NAC \NWC"4;
"S \NAC"
BN"33"92;
%"TAP"
"6","(-1600,3200)","2","mstr_standard","I79";
;
HDL_TAP"TRUE"
BODY_TYPE"PLUMBING"
CDS_LIB"mstr_standard";
"B \NAC \NWC"4;
"S \NAC"
BN"28"96;
%"TAP"
"6","(900,4800)","2","mstr_standard","I8";
;
HDL_TAP"TRUE"
BODY_TYPE"PLUMBING"
CDS_LIB"mstr_standard";
"B \NAC \NWC"1;
"S \NAC"
BN"14"167;
%"TAP"
"6","(-1600,3300)","2","mstr_standard","I80";
;
HDL_TAP"TRUE"
BODY_TYPE"PLUMBING"
CDS_LIB"mstr_standard";
"B \NAC \NWC"4;
"S \NAC"
BN"30"91;
%"TAP"
"6","(-1600,3250)","2","mstr_standard","I81";
;
HDL_TAP"TRUE"
BODY_TYPE"PLUMBING"
CDS_LIB"mstr_standard";
"B \NAC \NWC"4;
"S \NAC"
BN"31"90;
%"TAP"
"6","(-1600,3100)","2","mstr_standard","I82";
;
HDL_TAP"TRUE"
BODY_TYPE"PLUMBING"
CDS_LIB"mstr_standard";
"B \NAC \NWC"4;
"S \NAC"
BN"26"87;
%"TAP"
"6","(-1600,3150)","2","mstr_standard","I83";
;
HDL_TAP"TRUE"
BODY_TYPE"PLUMBING"
CDS_LIB"mstr_standard";
"B \NAC \NWC"4;
"S \NAC"
BN"29"95;
%"TAP"
"6","(-1600,3050)","2","mstr_standard","I84";
;
HDL_TAP"TRUE"
BODY_TYPE"PLUMBING"
CDS_LIB"mstr_standard";
"B \NAC \NWC"4;
"S \NAC"
BN"27"78;
%"TAP"
"6","(-1600,2950)","2","mstr_standard","I85";
;
HDL_TAP"TRUE"
BODY_TYPE"PLUMBING"
CDS_LIB"mstr_standard";
"B \NAC \NWC"4;
"S \NAC"
BN"25"84;
%"TAP"
"6","(-1600,3000)","2","mstr_standard","I86";
;
HDL_TAP"TRUE"
BODY_TYPE"PLUMBING"
CDS_LIB"mstr_standard";
"B \NAC \NWC"4;
"S \NAC"
BN"24"85;
%"TAP"
"6","(-1600,2850)","2","mstr_standard","I87";
;
HDL_TAP"TRUE"
BODY_TYPE"PLUMBING"
CDS_LIB"mstr_standard";
"B \NAC \NWC"4;
"S \NAC"
BN"23"82;
%"TAP"
"6","(-1600,2900)","2","mstr_standard","I88";
;
HDL_TAP"TRUE"
BODY_TYPE"PLUMBING"
CDS_LIB"mstr_standard";
"B \NAC \NWC"4;
"S \NAC"
BN"22"83;
%"TAP"
"6","(-1600,2800)","2","mstr_standard","I89";
;
HDL_TAP"TRUE"
BODY_TYPE"PLUMBING"
CDS_LIB"mstr_standard";
"B \NAC \NWC"4;
"S \NAC"
BN"20"86;
%"TAP"
"6","(900,4600)","2","mstr_standard","I9";
;
HDL_TAP"TRUE"
BODY_TYPE"PLUMBING"
CDS_LIB"mstr_standard";
"B \NAC \NWC"1;
"S \NAC"
BN"12"171;
%"TAP"
"6","(-1600,2750)","2","mstr_standard","I90";
;
HDL_TAP"TRUE"
BODY_TYPE"PLUMBING"
CDS_LIB"mstr_standard";
"B \NAC \NWC"4;
"S \NAC"
BN"21"81;
%"TAP"
"6","(-1600,2700)","2","mstr_standard","I91";
;
HDL_TAP"TRUE"
BODY_TYPE"PLUMBING"
CDS_LIB"mstr_standard";
"B \NAC \NWC"4;
"S \NAC"
BN"18"80;
%"TAP"
"6","(-1600,2650)","2","mstr_standard","I92";
;
HDL_TAP"TRUE"
BODY_TYPE"PLUMBING"
CDS_LIB"mstr_standard";
"B \NAC \NWC"4;
"S \NAC"
BN"19"79;
%"TAP"
"6","(-1600,2550)","2","mstr_standard","I93";
;
HDL_TAP"TRUE"
BODY_TYPE"PLUMBING"
CDS_LIB"mstr_standard";
"B \NAC \NWC"4;
"S \NAC"
BN"17"74;
%"TAP"
"6","(-1600,2600)","2","mstr_standard","I94";
;
HDL_TAP"TRUE"
BODY_TYPE"PLUMBING"
CDS_LIB"mstr_standard";
"B \NAC \NWC"4;
"S \NAC"
BN"16"77;
%"TAP"
"6","(-1600,2500)","2","mstr_standard","I95";
;
HDL_TAP"TRUE"
BODY_TYPE"PLUMBING"
CDS_LIB"mstr_standard";
"B \NAC \NWC"4;
"S \NAC"
BN"14"66;
%"TAP"
"6","(-1600,2450)","2","mstr_standard","I96";
;
HDL_TAP"TRUE"
BODY_TYPE"PLUMBING"
CDS_LIB"mstr_standard";
"B \NAC \NWC"4;
"S \NAC"
BN"15"73;
%"TAP"
"6","(-1600,2350)","2","mstr_standard","I97";
;
HDL_TAP"TRUE"
BODY_TYPE"PLUMBING"
CDS_LIB"mstr_standard";
"B \NAC \NWC"4;
"S \NAC"
BN"13"72;
%"TAP"
"6","(-1600,2400)","2","mstr_standard","I98";
;
HDL_TAP"TRUE"
BODY_TYPE"PLUMBING"
CDS_LIB"mstr_standard";
"B \NAC \NWC"4;
"S \NAC"
BN"12"76;
%"TAP"
"6","(-1600,2300)","2","mstr_standard","I99";
;
HDL_TAP"TRUE"
BODY_TYPE"PLUMBING"
CDS_LIB"mstr_standard";
"B \NAC \NWC"4;
"S \NAC"
BN"10"71;
END.
